# T6G (Grand Teton) — schematic netlist excerpt (pin names and nets, part order shuffled) for the footprints in the layout excerpt that follows; sources: Cadence DE-HDL packaged netlist, KiCad conversion of 04192023_DAF0TMB3IC0_F0TG_MB_C_brd_V02_OCP.brd

R1719  Q_RES  33.2 1% CHIP  pkg 0402LF  page 132 : A = OCP_SFF_AUX_PWR_EN ; B = OCP_SFF_AUX_PWR_EN_R1
PL54  Q_INDUCTOR  90NH/155A IND  pkg SMLF  page 225 : \1\ = SW_PVDD11_S3_P1_SW1 ; \2\ = PVDD11_S3_P1
C771  Q_CAP_DIFFBUS  DIFF BUS_0.22UF 6.3V 20% X6S  pkg C0201  page 66 : \1\ = P5E_CPU1_P2_TX_C_DP<1> ; \2\ = P5E_CPU1_P2_TX_DP<1>

(kicad_pcb
	(version 20260206)
	(generator "pcbnew")
	(generator_version "10.0")
	(general
		(thickness 1.6)
		(legacy_teardrops no)
	)
	(paper "A4")
	(title_block
		(title "04192023_DAF0TMB3IC0_F0TG_MB_C_brd_V02_OCP.brd")
		(comment 1 "Grand Teton / footprints 4197-4199 of 8354")
	)
	(layers
		(0 "F.Cu" signal "TOP")
		(4 "In1.Cu" signal "GND")
		(6 "In2.Cu" signal "IN1")
		(8 "In3.Cu" signal "GND1")
		(10 "In4.Cu" signal "IN2")
		(12 "In5.Cu" signal "GND2")
		(14 "In6.Cu" signal "IN3")
		(16 "In7.Cu" signal "GND3")
		(18 "In8.Cu" signal "VCC")
		(20 "In9.Cu" signal "VCC1")
		(22 "In10.Cu" signal "GND4")
		(24 "In11.Cu" signal "IN4")
		(26 "In12.Cu" signal "GND5")
		(28 "In13.Cu" signal "IN5")
		(30 "In14.Cu" signal "GND6")
		(32 "In15.Cu" signal "IN6")
		(34 "In16.Cu" signal "GND7")
		(2 "B.Cu" signal "BOTTOM")
		(9 "F.Adhes" user "F.Adhesive")
		(11 "B.Adhes" user "B.Adhesive")
		(13 "F.Paste" user "Package Geometry/Pastemask Top")
		(15 "B.Paste" user "Package Geometry/Pastemask Bottom")
		(5 "F.SilkS" user "Ref Des/Silkscreen Top")
		(7 "B.SilkS" user "Ref Des/Silkscreen Bottom")
		(1 "F.Mask" user "Board Geometry/Soldermask Top")
		(3 "B.Mask" user "Board Geometry/Soldermask Bottom")
		(17 "Dwgs.User" user "User.Drawings")
		(19 "Cmts.User" user "User.Comments")
		(21 "Eco1.User" user "User.Eco1")
		(23 "Eco2.User" user "User.Eco2")
		(25 "Edge.Cuts" user "Board Geometry/Outline")
		(27 "Margin" user)
		(31 "F.CrtYd" user "Package Geometry/Place Bound Top")
		(29 "B.CrtYd" user "Package Geometry/Place Bound Bottom")
		(35 "F.Fab" user "Ref Des/Assembly Top")
		(33 "B.Fab" user "Ref Des/Assembly Bottom")
	)
	(footprint ""
		(layer "F.Cu")
		(at 182.919878 -342.462358 -90)
		(property "Reference" "PL54"
			(at -15.116048 5.983986 0)
			(unlocked yes)
			(layer "F.SilkS")
			(effects
				(font
					(size 0.7874 0.5842)
					(thickness 0.1524)
				)
				(justify left)
			)
		)
		(property "Value" ""
			(at 0 0 270)
			(layer "F.Fab")
			(effects
				(font
					(size 1.27 1.27)
				)
			)
		)
		(duplicate_pad_numbers_are_jumpers no)
		(fp_line
			(start -4.99999 3.849878)
			(end -4.99999 2.23901)
			(stroke
				(width 0.1524)
				(type default)
			)
			(layer "F.SilkS")
		)
		(fp_line
			(start 4.99999 3.849878)
			(end -4.99999 3.849878)
			(stroke
				(width 0.1524)
				(type default)
			)
			(layer "F.SilkS")
		)
		(fp_line
			(start 4.99999 2.23901)
			(end 4.99999 3.849878)
			(stroke
				(width 0.1524)
				(type default)
			)
			(layer "F.SilkS")
		)
		(fp_line
			(start -4.99999 -2.23901)
			(end -4.99999 -3.849878)
			(stroke
				(width 0.1524)
				(type default)
			)
			(layer "F.SilkS")
		)
		(fp_line
			(start -4.99999 -3.849878)
			(end 4.99999 -3.849878)
			(stroke
				(width 0.1524)
				(type default)
			)
			(layer "F.SilkS")
		)
		(fp_line
			(start 4.99999 -3.849878)
			(end 4.99999 -2.23901)
			(stroke
				(width 0.1524)
				(type default)
			)
			(layer "F.SilkS")
		)
		(fp_line
			(start -4.99999 3.849878)
			(end -4.99999 -3.849878)
			(stroke
				(width 0.1)
				(type default)
			)
			(layer "F.Fab")
		)
		(fp_line
			(start 4.99999 3.849878)
			(end -4.99999 3.849878)
			(stroke
				(width 0.1)
				(type default)
			)
			(layer "F.Fab")
		)
		(fp_line
			(start -4.99999 -3.849878)
			(end 4.99999 -3.849878)
			(stroke
				(width 0.1)
				(type default)
			)
			(layer "F.Fab")
		)
		(fp_line
			(start 4.99999 -3.849878)
			(end 4.99999 3.849878)
			(stroke
				(width 0.1)
				(type default)
			)
			(layer "F.Fab")
		)
		(pad "1" smd rect
			(at -3.299968 0 270)
			(size 3.302 4.2164)
			(layers "F.Cu" "F.Mask" "F.Paste")
			(net "SW_PVDD11_S3_P1_SW1")
		)
		(pad "2" smd rect
			(at 3.299968 0 270)
			(size 3.302 4.2164)
			(layers "F.Cu" "F.Mask" "F.Paste")
			(net "PVDD11_S3_P1")
		)
	)
	(footprint ""
		(layer "F.Cu")
		(at 142.595092 -375.94286 180)
		(property "Reference" "C771"
			(at 0 0 180)
			(layer "F.SilkS")
			(hide yes)
			(effects
				(font
					(size 1.27 1.27)
				)
			)
		)
		(property "Value" ""
			(at 0 0 180)
			(layer "F.Fab")
			(effects
				(font
					(size 1.27 1.27)
				)
			)
		)
		(duplicate_pad_numbers_are_jumpers no)
		(fp_line
			(start 0.299974 0.150114)
			(end -0.299974 0.150114)
			(stroke
				(width 0.1)
				(type default)
			)
			(layer "F.Fab")
		)
		(fp_line
			(start 0.299974 -0.150114)
			(end 0.299974 0.150114)
			(stroke
				(width 0.1)
				(type default)
			)
			(layer "F.Fab")
		)
		(fp_line
			(start -0.299974 0.150114)
			(end -0.299974 -0.150114)
			(stroke
				(width 0.1)
				(type default)
			)
			(layer "F.Fab")
		)
		(fp_line
			(start -0.299974 -0.150114)
			(end 0.299974 -0.150114)
			(stroke
				(width 0.1)
				(type default)
			)
			(layer "F.Fab")
		)
		(pad "1" smd rect
			(at -0.2667 0 180)
			(size 0.3048 0.381)
			(layers "F.Cu" "F.Mask" "F.Paste")
			(net "P5E_CPU1_P2_TX_C_DP<1>")
		)
		(pad "2" smd rect
			(at 0.2667 0 180)
			(size 0.3048 0.381)
			(layers "F.Cu" "F.Mask" "F.Paste")
			(net "P5E_CPU1_P2_TX_DP<1>")
		)
	)
	(footprint ""
		(layer "F.Cu")
		(at 455.617834 -99.164394)
		(property "Reference" "R1719"
			(at 0 0 0)
			(layer "F.SilkS")
			(hide yes)
			(effects
				(font
					(size 1.27 1.27)
				)
			)
		)
		(property "Value" ""
			(at 0 0 0)
			(layer "F.Fab")
			(effects
				(font
					(size 1.27 1.27)
				)
			)
		)
		(duplicate_pad_numbers_are_jumpers no)
		(fp_line
			(start -0.7874 -0.4064)
			(end 0.7874 -0.4064)
			(stroke
				(width 0.1524)
				(type default)
			)
			(layer "F.SilkS")
		)
		(fp_line
			(start -0.7874 0.4064)
			(end -0.7874 -0.4064)
			(stroke
				(width 0.1524)
				(type default)
			)
			(layer "F.SilkS")
		)
		(fp_line
			(start 0.7874 -0.4064)
			(end 0.7874 0.4064)
			(stroke
				(width 0.1524)
				(type default)
			)
			(layer "F.SilkS")
		)
		(fp_line
			(start 0.7874 0.4064)
			(end -0.7874 0.4064)
			(stroke
				(width 0.1524)
				(type default)
			)
			(layer "F.SilkS")
		)
		(fp_line
			(start -0.67945 -0.305054)
			(end -0.12065 -0.305054)
			(stroke
				(width 0.1)
				(type default)
			)
			(layer "F.Fab")
		)
		(fp_line
			(start -0.67945 0.3048)
			(end -0.67945 -0.305054)
			(stroke
				(width 0.1)
				(type default)
			)
			(layer "F.Fab")
		)
		(fp_line
			(start -0.12065 -0.305054)
			(end -0.12065 -0.2794)
			(stroke
				(width 0.1)
				(type default)
			)
			(layer "F.Fab")
		)
		(fp_line
			(start -0.12065 -0.2794)
			(end 0.12065 -0.2794)
			(stroke
				(width 0.1)
				(type default)
			)
			(layer "F.Fab")
		)
		(fp_line
			(start -0.12065 0.2794)
			(end -0.12065 0.3048)
			(stroke
				(width 0.1)
				(type default)
			)
			(layer "F.Fab")
		)
		(fp_line
			(start -0.12065 0.3048)
			(end -0.67945 0.3048)
			(stroke
				(width 0.1)
				(type default)
			)
			(layer "F.Fab")
		)
		(fp_line
			(start 0.120396 0.2794)
			(end -0.12065 0.2794)
			(stroke
				(width 0.1)
				(type default)
			)
			(layer "F.Fab")
		)
		(fp_line
			(start 0.120396 0.3048)
			(end 0.120396 0.2794)
			(stroke
				(width 0.1)
				(type default)
			)
			(layer "F.Fab")
		)
		(fp_line
			(start 0.12065 -0.3048)
			(end 0.67945 -0.3048)
			(stroke
				(width 0.1)
				(type default)
			)
			(layer "F.Fab")
		)
		(fp_line
			(start 0.12065 -0.2794)
			(end 0.12065 -0.3048)
			(stroke
				(width 0.1)
				(type default)
			)
			(layer "F.Fab")
		)
		(fp_line
			(start 0.67945 -0.3048)
			(end 0.67945 0.3048)
			(stroke
				(width 0.1)
				(type default)
			)
			(layer "F.Fab")
		)
		(fp_line
			(start 0.67945 0.3048)
			(end 0.120396 0.3048)
			(stroke
				(width 0.1)
				(type default)
			)
			(layer "F.Fab")
		)
		(pad "1" smd circle
			(at -0.40005 0)
			(size 0 0)
			(layers "F.Cu" "F.Mask" "F.Paste")
			(net "OCP_SFF_AUX_PWR_EN")
		)
		(pad "2" smd circle
			(at 0.40005 0)
			(size 0 0)
			(layers "F.Cu" "F.Mask" "F.Paste")
			(net "OCP_SFF_AUX_PWR_EN_R1")
		)
	)
)
